(kicad_pcb
	(version 20260206)
	(generator "pcbnew")
	(generator_version "10.0")
	(general
		(thickness 1.6)
		(legacy_teardrops no)
	)
	(paper "A4")
	(title_block
		(title "Bryce Canyon_IOM_M2_16342-2_OCP.brd")
		(comment 1 "Bryce Canyon / footprints 243-249 of 1146")
	)
	(layers
		(0 "F.Cu" signal "TOP")
		(4 "In1.Cu" signal "L2GND")
		(6 "In2.Cu" signal "L3")
		(8 "In3.Cu" signal "L4VCC")
		(10 "In4.Cu" signal "L5VCC")
		(12 "In5.Cu" signal "L6")
		(14 "In6.Cu" signal "L7GND")
		(2 "B.Cu" signal "BOTTOM")
		(9 "F.Adhes" user "F.Adhesive")
		(11 "B.Adhes" user "B.Adhesive")
		(13 "F.Paste" user "Package Geometry/Pastemask Top")
		(15 "B.Paste" user "Package Geometry/Pastemask Bottom")
		(5 "F.SilkS" user "Ref Des/Silkscreen Top")
		(7 "B.SilkS" user "Ref Des/Silkscreen Bottom")
		(1 "F.Mask" user "Board Geometry/Soldermask Top")
		(3 "B.Mask" user "Board Geometry/Soldermask Bottom")
		(17 "Dwgs.User" user "User.Drawings")
		(19 "Cmts.User" user "User.Comments")
		(21 "Eco1.User" user "User.Eco1")
		(23 "Eco2.User" user "User.Eco2")
		(25 "Edge.Cuts" user "Board Geometry/Outline")
		(27 "Margin" user)
		(31 "F.CrtYd" user "Package Geometry/Place Bound Top")
		(29 "B.CrtYd" user "Package Geometry/Place Bound Bottom")
		(35 "F.Fab" user "Ref Des/Assembly Top")
		(33 "B.Fab" user "Ref Des/Assembly Bottom")
	)
	(footprint ""
		(layer "F.Cu")
		(at 24.042116 -162.3441 90)
		(property "Reference" "C225"
			(at 0 0 90)
			(layer "F.SilkS")
			(hide yes)
			(effects
				(font
					(size 1.27 1.27)
				)
			)
		)
		(property "Value" "SC10U6D3V5KX-4GP"
			(at -0.0762 -6.1214 90)
			(unlocked yes)
			(layer "F.Fab")
			(hide yes)
			(effects
				(font
					(size 1.016 1.016)
					(thickness 0.1524)
				)
			)
		)
		(property "Device Type" "C805H58"
			(at -0.0762 -8.1534 90)
			(unlocked yes)
			(layer "F.Fab")
			(hide yes)
			(effects
				(font
					(size 1.016 1.016)
					(thickness 0.1524)
				)
			)
		)
		(duplicate_pad_numbers_are_jumpers no)
		(fp_line
			(start 0.635 0)
			(end -0.635 0)
			(stroke
				(width 0.508)
				(type default)
			)
			(layer "F.SilkS")
		)
		(fp_rect
			(start -0.9652 1.778)
			(end 0.9652 -1.778)
			(stroke
				(width 0)
				(type default)
			)
			(fill no)
			(layer "F.CrtYd")
		)
		(fp_poly
			(pts
				(xy -0.9652 -1.778) (xy 0.9652 -1.778) (xy 0.9652 1.778) (xy -0.9652 1.778)
			)
			(stroke
				(width 0)
				(type default)
			)
			(fill no)
			(layer "F.Fab")
		)
		(pad "1" smd rect
			(at 0 -0.9652 90)
			(size 1.397 1.143)
			(layers "F.Cu" "F.Mask" "F.Paste")
			(net "TPS74801_P1V2_STBY_OUT")
		)
		(pad "2" smd rect
			(at 0 0.9652 90)
			(size 1.397 1.143)
			(layers "F.Cu" "F.Mask" "F.Paste")
			(net "GND")
		)
	)
	(footprint ""
		(layer "F.Cu")
		(at 93.748352 -134.716774 -90)
		(property "Reference" "U26"
			(at 0 0 270)
			(layer "F.SilkS")
			(hide yes)
			(effects
				(font
					(size 1.27 1.27)
				)
			)
		)
		(property "Value" "24LC64-I-SN-GP"
			(at -3.707384 -1.5367 270)
			(unlocked yes)
			(layer "F.Fab")
			(hide yes)
			(effects
				(font
					(size 1.016 1.016)
					(thickness 0.1524)
				)
			)
		)
		(property "Device Type" "SOIC8H69"
			(at -3.707384 -3.0607 270)
			(unlocked yes)
			(layer "F.Fab")
			(hide yes)
			(effects
				(font
					(size 1.016 1.016)
					(thickness 0.1524)
				)
			)
		)
		(duplicate_pad_numbers_are_jumpers no)
		(fp_line
			(start -2.6289 3.4417)
			(end -2.6289 1.4732)
			(stroke
				(width 0.381)
				(type default)
			)
			(layer "F.SilkS")
		)
		(fp_line
			(start -2.7432 1.4224)
			(end -2.6416 1.4224)
			(stroke
				(width 0.1524)
				(type default)
			)
			(layer "F.SilkS")
		)
		(fp_line
			(start -2.7432 1.4224)
			(end 2.1336 1.4224)
			(stroke
				(width 0.1524)
				(type default)
			)
			(layer "F.SilkS")
		)
		(fp_line
			(start 2.1336 1.4224)
			(end 2.1336 -1.4224)
			(stroke
				(width 0.1524)
				(type default)
			)
			(layer "F.SilkS")
		)
		(fp_line
			(start -2.1844 -0.0508)
			(end -2.7178 0.508)
			(stroke
				(width 0.1524)
				(type default)
			)
			(layer "F.SilkS")
		)
		(fp_line
			(start -2.7178 -0.508)
			(end -2.1844 -0.0508)
			(stroke
				(width 0.1524)
				(type default)
			)
			(layer "F.SilkS")
		)
		(fp_line
			(start -2.7432 -1.4224)
			(end -2.7432 1.4224)
			(stroke
				(width 0.1524)
				(type default)
			)
			(layer "F.SilkS")
		)
		(fp_line
			(start 2.1336 -1.4224)
			(end -2.7432 -1.4224)
			(stroke
				(width 0.1524)
				(type default)
			)
			(layer "F.SilkS")
		)
		(fp_poly
			(pts
				(xy -2.2098 -1.4224) (xy -2.2098 1.4224) (xy 2.2098 1.4224) (xy 2.2098 -1.4224)
			)
			(stroke
				(width 0)
				(type default)
			)
			(fill yes)
			(layer "F.SilkS")
		)
		(fp_rect
			(start -2.450084 2.999994)
			(end 2.450084 -2.999994)
			(stroke
				(width 0)
				(type default)
			)
			(fill no)
			(layer "F.CrtYd")
		)
		(fp_poly
			(pts
				(xy -2.8194 3.6322) (xy -2.8194 -3.6322) (xy 2.8194 -3.6322) (xy 2.8194 1.18364) (xy 2.450084 1.18364)
				(xy 2.450084 -2.999994) (xy -2.450084 -2.999994) (xy -2.450084 2.999994) (xy 2.450084 2.999994)
				(xy 2.450084 1.18618) (xy 2.8194 1.18618) (xy 2.8194 3.6322)
			)
			(stroke
				(width 0)
				(type default)
			)
			(fill no)
			(layer "F.CrtYd")
		)
		(fp_rect
			(start -2.8194 3.6322)
			(end 2.8194 -3.6322)
			(stroke
				(width 0)
				(type default)
			)
			(fill no)
			(layer "F.Fab")
		)
		(pad "1" smd rect
			(at -1.905 2.54 270)
			(size 0.635 1.651)
			(layers "F.Cu" "F.Mask" "F.Paste")
			(net "EEPROM_A0")
		)
		(pad "2" smd rect
			(at -0.635 2.54 270)
			(size 0.635 1.651)
			(layers "F.Cu" "F.Mask" "F.Paste")
			(net "EEPROM_A1")
		)
		(pad "3" smd rect
			(at 0.635 2.54 270)
			(size 0.635 1.651)
			(layers "F.Cu" "F.Mask" "F.Paste")
			(net "EEPROM_A2")
		)
		(pad "4" smd rect
			(at 1.905 2.54 270)
			(size 0.635 1.651)
			(layers "F.Cu" "F.Mask" "F.Paste")
			(net "GND")
		)
		(pad "5" smd rect
			(at 1.905 -2.54 270)
			(size 0.635 1.651)
			(layers "F.Cu" "F.Mask" "F.Paste")
			(net "I2C_IOM_SDA")
		)
		(pad "6" smd rect
			(at 0.635 -2.54 270)
			(size 0.635 1.651)
			(layers "F.Cu" "F.Mask" "F.Paste")
			(net "I2C_IOM_SCL")
		)
		(pad "7" smd rect
			(at -0.635 -2.54 270)
			(size 0.635 1.651)
			(layers "F.Cu" "F.Mask" "F.Paste")
			(net "EEPROM_WP")
		)
		(pad "8" smd rect
			(at -1.905 -2.54 270)
			(size 0.635 1.651)
			(layers "F.Cu" "F.Mask" "F.Paste")
			(net "P3V3_STBY")
		)
	)
	(footprint ""
		(layer "F.Cu")
		(at 85.46973 -143.202152 -90)
		(property "Reference" "R132"
			(at 0 0 270)
			(layer "F.SilkS")
			(hide yes)
			(effects
				(font
					(size 1.27 1.27)
				)
			)
		)
		(property "Value" "0R2J-2-GP"
			(at 0.064008 -3.993896 270)
			(unlocked yes)
			(layer "F.Fab")
			(hide yes)
			(effects
				(font
					(size 1.016 1.016)
					(thickness 0.1524)
				)
			)
		)
		(property "Device Type" "R402H16"
			(at 0.064008 -5.517896 270)
			(unlocked yes)
			(layer "F.Fab")
			(hide yes)
			(effects
				(font
					(size 1.016 1.016)
					(thickness 0.1524)
				)
			)
		)
		(duplicate_pad_numbers_are_jumpers no)
		(fp_line
			(start -0.508 -0.9398)
			(end -0.508 0.9398)
			(stroke
				(width 0.1524)
				(type default)
			)
			(layer "F.SilkS")
		)
		(fp_line
			(start 0.508 -0.9398)
			(end -0.508 -0.9398)
			(stroke
				(width 0.1524)
				(type default)
			)
			(layer "F.SilkS")
		)
		(fp_rect
			(start -0.508 0.9398)
			(end 0.508 -0.9398)
			(stroke
				(width 0)
				(type default)
			)
			(fill no)
			(layer "F.CrtYd")
		)
		(fp_rect
			(start -0.508 0.9398)
			(end 0.508 -0.9398)
			(stroke
				(width 0)
				(type default)
			)
			(fill no)
			(layer "F.Fab")
		)
		(pad "1" smd custom
			(at 0 -0.4445 270)
			(size 0.1397 0.1397)
			(layers "F.Cu" "F.Mask" "F.Paste")
			(net "I2C_SCC_SDA")
			(options
				(clearance outline)
				(anchor circle)
			)
			(primitives
				(gr_poly
					(pts
						(arc
							(start -0.1778 -0.2794)
							(mid -0.249642 -0.249642)
							(end -0.2794 -0.1778)
						)
						(arc
							(start -0.2794 0.1778)
							(mid -0.249642 0.249642)
							(end -0.1778 0.2794)
						)
						(arc
							(start 0.1778 0.2794)
							(mid 0.249642 0.249642)
							(end 0.2794 0.1778)
						)
						(arc
							(start 0.2794 -0.1778)
							(mid 0.249642 -0.249642)
							(end 0.1778 -0.2794)
						)
					)
					(width 0)
					(fill yes)
				)
			)
		)
		(pad "2" smd custom
			(at 0 0.4445 270)
			(size 0.1397 0.1397)
			(layers "F.Cu" "F.Mask" "F.Paste")
			(net "I2C_SCC_SDA_R")
			(options
				(clearance outline)
				(anchor circle)
			)
			(primitives
				(gr_poly
					(pts
						(arc
							(start -0.1778 -0.2794)
							(mid -0.249642 -0.249642)
							(end -0.2794 -0.1778)
						)
						(arc
							(start -0.2794 0.1778)
							(mid -0.249642 0.249642)
							(end -0.1778 0.2794)
						)
						(arc
							(start 0.1778 0.2794)
							(mid 0.249642 0.249642)
							(end 0.2794 0.1778)
						)
						(arc
							(start 0.2794 -0.1778)
							(mid 0.249642 -0.249642)
							(end 0.1778 -0.2794)
						)
					)
					(width 0)
					(fill yes)
				)
			)
		)
	)
	(footprint ""
		(layer "F.Cu")
		(at 35.58286 -157.740858)
		(property "Reference" "TP57"
			(at 0 0 0)
			(layer "F.SilkS")
			(hide yes)
			(effects
				(font
					(size 1.27 1.27)
				)
			)
		)
		(property "Value" "TPAD28-2-GP"
			(at -0.0127 -1.6637 0)
			(unlocked yes)
			(layer "F.Fab")
			(hide yes)
			(effects
				(font
					(size 1.016 1.016)
					(thickness 0.1524)
				)
			)
		)
		(property "Device Type" "TPAD28"
			(at -0.0127 -3.1877 0)
			(unlocked yes)
			(layer "F.Fab")
			(hide yes)
			(effects
				(font
					(size 1.016 1.016)
					(thickness 0.1524)
				)
			)
		)
		(duplicate_pad_numbers_are_jumpers no)
		(fp_poly
			(pts
				(arc
					(start 0.3556 0)
					(mid -0.3556 0)
					(end 0.3556 0)
				)
			)
			(stroke
				(width 0)
				(type default)
			)
			(fill no)
			(layer "F.CrtYd")
		)
		(fp_poly
			(pts
				(arc
					(start 0.6096 0)
					(mid -0.6096 0)
					(end 0.6096 0)
				)
			)
			(stroke
				(width 0)
				(type default)
			)
			(fill no)
			(layer "F.Fab")
		)
		(pad "1" smd circle
			(at 0 0)
			(size 0.7112 0.7112)
			(layers "F.Cu" "F.Mask" "F.Paste")
			(net "TP_BMC_GPION5")
		)
	)
	(footprint ""
		(layer "F.Cu")
		(at 74.442828 -175.754538 90)
		(property "Reference" "R506"
			(at 0 0 90)
			(layer "F.SilkS")
			(hide yes)
			(effects
				(font
					(size 1.27 1.27)
				)
			)
		)
		(property "Value" "1K69R2F-2-GP"
			(at 0.064008 -3.993896 90)
			(unlocked yes)
			(layer "F.Fab")
			(hide yes)
			(effects
				(font
					(size 1.016 1.016)
					(thickness 0.1524)
				)
			)
		)
		(property "Device Type" "R402H16"
			(at 0.064008 -5.517896 90)
			(unlocked yes)
			(layer "F.Fab")
			(hide yes)
			(effects
				(font
					(size 1.016 1.016)
					(thickness 0.1524)
				)
			)
		)
		(duplicate_pad_numbers_are_jumpers no)
		(fp_line
			(start 0.508 -0.9398)
			(end -0.508 -0.9398)
			(stroke
				(width 0.1524)
				(type default)
			)
			(layer "F.SilkS")
		)
		(fp_line
			(start -0.508 -0.9398)
			(end -0.508 0.9398)
			(stroke
				(width 0.1524)
				(type default)
			)
			(layer "F.SilkS")
		)
		(fp_rect
			(start -0.508 0.9398)
			(end 0.508 -0.9398)
			(stroke
				(width 0)
				(type default)
			)
			(fill no)
			(layer "F.CrtYd")
		)
		(fp_rect
			(start -0.508 0.9398)
			(end 0.508 -0.9398)
			(stroke
				(width 0)
				(type default)
			)
			(fill no)
			(layer "F.Fab")
		)
		(pad "1" smd custom
			(at 0 -0.4445 90)
			(size 0.1397 0.1397)
			(layers "F.Cu" "F.Mask" "F.Paste")
			(net "TPS74801_P2V5_STBY_FB")
			(options
				(clearance outline)
				(anchor circle)
			)
			(primitives
				(gr_poly
					(pts
						(arc
							(start -0.1778 -0.2794)
							(mid -0.249642 -0.249642)
							(end -0.2794 -0.1778)
						)
						(arc
							(start -0.2794 0.1778)
							(mid -0.249642 0.249642)
							(end -0.1778 0.2794)
						)
						(arc
							(start 0.1778 0.2794)
							(mid 0.249642 0.249642)
							(end 0.2794 0.1778)
						)
						(arc
							(start 0.2794 -0.1778)
							(mid 0.249642 -0.249642)
							(end 0.1778 -0.2794)
						)
					)
					(width 0)
					(fill yes)
				)
			)
		)
		(pad "2" smd custom
			(at 0 0.4445 90)
			(size 0.1397 0.1397)
			(layers "F.Cu" "F.Mask" "F.Paste")
			(net "GND")
			(options
				(clearance outline)
				(anchor circle)
			)
			(primitives
				(gr_poly
					(pts
						(arc
							(start -0.1778 -0.2794)
							(mid -0.249642 -0.249642)
							(end -0.2794 -0.1778)
						)
						(arc
							(start -0.2794 0.1778)
							(mid -0.249642 0.249642)
							(end -0.1778 0.2794)
						)
						(arc
							(start 0.1778 0.2794)
							(mid 0.249642 0.249642)
							(end 0.2794 0.1778)
						)
						(arc
							(start 0.2794 -0.1778)
							(mid 0.249642 -0.249642)
							(end 0.1778 -0.2794)
						)
					)
					(width 0)
					(fill yes)
				)
			)
		)
	)
	(footprint ""
		(layer "F.Cu")
		(at 47.491904 -161.231072 180)
		(property "Reference" "R204"
			(at 0 0 180)
			(layer "F.SilkS")
			(hide yes)
			(effects
				(font
					(size 1.27 1.27)
				)
			)
		)
		(property "Value" "2K2R2F-GP"
			(at 0.064008 -3.993896 180)
			(unlocked yes)
			(layer "F.Fab")
			(hide yes)
			(effects
				(font
					(size 1.016 1.016)
					(thickness 0.1524)
				)
			)
		)
		(property "Device Type" "R402H16"
			(at 0.064008 -5.517896 180)
			(unlocked yes)
			(layer "F.Fab")
			(hide yes)
			(effects
				(font
					(size 1.016 1.016)
					(thickness 0.1524)
				)
			)
		)
		(duplicate_pad_numbers_are_jumpers no)
		(fp_line
			(start 0.508 -0.9398)
			(end -0.508 -0.9398)
			(stroke
				(width 0.1524)
				(type default)
			)
			(layer "F.SilkS")
		)
		(fp_line
			(start -0.508 -0.9398)
			(end -0.508 0.9398)
			(stroke
				(width 0.1524)
				(type default)
			)
			(layer "F.SilkS")
		)
		(fp_rect
			(start -0.508 0.9398)
			(end 0.508 -0.9398)
			(stroke
				(width 0)
				(type default)
			)
			(fill no)
			(layer "F.CrtYd")
		)
		(fp_rect
			(start -0.508 0.9398)
			(end 0.508 -0.9398)
			(stroke
				(width 0)
				(type default)
			)
			(fill no)
			(layer "F.Fab")
		)
		(pad "1" smd custom
			(at 0 -0.4445 180)
			(size 0.1397 0.1397)
			(layers "F.Cu" "F.Mask" "F.Paste")
			(net "I2C_DPB_MISC_SDA_OUT")
			(options
				(clearance outline)
				(anchor circle)
			)
			(primitives
				(gr_poly
					(pts
						(arc
							(start -0.1778 -0.2794)
							(mid -0.249642 -0.249642)
							(end -0.2794 -0.1778)
						)
						(arc
							(start -0.2794 0.1778)
							(mid -0.249642 0.249642)
							(end -0.1778 0.2794)
						)
						(arc
							(start 0.1778 0.2794)
							(mid 0.249642 0.249642)
							(end 0.2794 0.1778)
						)
						(arc
							(start 0.2794 -0.1778)
							(mid 0.249642 -0.249642)
							(end 0.1778 -0.2794)
						)
					)
					(width 0)
					(fill yes)
				)
			)
		)
		(pad "2" smd custom
			(at 0 0.4445 180)
			(size 0.1397 0.1397)
			(layers "F.Cu" "F.Mask" "F.Paste")
			(net "P3V3_STBY")
			(options
				(clearance outline)
				(anchor circle)
			)
			(primitives
				(gr_poly
					(pts
						(arc
							(start -0.1778 -0.2794)
							(mid -0.249642 -0.249642)
							(end -0.2794 -0.1778)
						)
						(arc
							(start -0.2794 0.1778)
							(mid -0.249642 0.249642)
							(end -0.1778 0.2794)
						)
						(arc
							(start 0.1778 0.2794)
							(mid 0.249642 0.249642)
							(end 0.2794 0.1778)
						)
						(arc
							(start 0.2794 -0.1778)
							(mid 0.249642 -0.249642)
							(end 0.1778 -0.2794)
						)
					)
					(width 0)
					(fill yes)
				)
			)
		)
	)
	(footprint ""
		(layer "F.Cu")
		(at 93.3958 -37.8206 180)
		(property "Reference" "C246"
			(at 0 0 180)
			(layer "F.SilkS")
			(hide yes)
			(effects
				(font
					(size 1.27 1.27)
				)
			)
		)
		(property "Value" "ST150U16VDM-3-GP"
			(at 0 -9.6012 180)
			(unlocked yes)
			(layer "F.Fab")
			(hide yes)
			(effects
				(font
					(size 1.016 1.016)
					(thickness 0.1524)
				)
			)
		)
		(property "Device Type" "CT7343H119"
			(at 0 -11.1252 180)
			(unlocked yes)
			(layer "F.Fab")
			(hide yes)
			(effects
				(font
					(size 1.016 1.016)
					(thickness 0.1524)
				)
			)
		)
		(duplicate_pad_numbers_are_jumpers no)
		(fp_line
			(start 2.286 4.8768)
			(end -2.286 4.8768)
			(stroke
				(width 0.1524)
				(type default)
			)
			(layer "F.SilkS")
		)
		(fp_line
			(start 2.286 2.032)
			(end 2.286 4.8768)
			(stroke
				(width 0.1524)
				(type default)
			)
			(layer "F.SilkS")
		)
		(fp_line
			(start 2.286 -2.032)
			(end 2.286 -4.8768)
			(stroke
				(width 0.1524)
				(type default)
			)
			(layer "F.SilkS")
		)
		(fp_line
			(start 2.286 -4.8768)
			(end -2.286 -4.8768)
			(stroke
				(width 0.1524)
				(type default)
			)
			(layer "F.SilkS")
		)
		(fp_line
			(start 2.1082 -4.699)
			(end -2.1082 -4.699)
			(stroke
				(width 0.508)
				(type default)
			)
			(layer "F.SilkS")
		)
		(fp_line
			(start -2.286 4.8768)
			(end -2.286 2.032)
			(stroke
				(width 0.1524)
				(type default)
			)
			(layer "F.SilkS")
		)
		(fp_line
			(start -2.286 -4.8768)
			(end -2.286 -2.032)
			(stroke
				(width 0.1524)
				(type default)
			)
			(layer "F.SilkS")
		)
		(fp_rect
			(start -2.1463 3.6449)
			(end 2.1463 -3.6449)
			(stroke
				(width 0)
				(type default)
			)
			(fill no)
			(layer "F.CrtYd")
		)
		(fp_poly
			(pts
				(xy -2.54 4.953) (xy -2.54 4.2926) (xy -3.81 4.2926) (xy -3.81 -4.2926) (xy -2.54 -4.2926) (xy -2.54 -4.953)
				(xy 2.54 -4.953) (xy 2.54 -4.2926) (xy 3.81 -4.2926) (xy 3.81 -1.6256) (xy 2.1463 -1.6256) (xy 2.1463 -3.6449)
				(xy -2.1463 -3.6449) (xy -2.1463 3.6449) (xy 2.1463 3.6449) (xy 2.1463 -1.6129) (xy 3.81 -1.6129)
				(xy 3.81 4.2926) (xy 2.54 4.2926) (xy 2.54 4.953)
			)
			(stroke
				(width 0)
				(type default)
			)
			(fill no)
			(layer "F.CrtYd")
		)
		(fp_rect
			(start 2.54 4.2926)
			(end 3.81 -4.2926)
			(stroke
				(width 0)
				(type default)
			)
			(fill no)
			(layer "F.Fab")
		)
		(fp_rect
			(start -2.54 4.953)
			(end 2.54 -4.953)
			(stroke
				(width 0)
				(type default)
			)
			(fill no)
			(layer "F.Fab")
		)
		(fp_rect
			(start -3.81 4.2926)
			(end -2.54 -4.2926)
			(stroke
				(width 0)
				(type default)
			)
			(fill no)
			(layer "F.Fab")
		)
		(pad "1" smd rect
			(at 0 -3.1496 180)
			(size 2.413 2.286)
			(layers "F.Cu" "F.Mask" "F.Paste")
			(net "P5V_USB")
		)
		(pad "2" smd rect
			(at 0 3.1496 180)
			(size 2.413 2.286)
			(layers "F.Cu" "F.Mask" "F.Paste")
			(net "GND")
		)
		(zone
			(layer "F.Cu")
			(hatch none 0.5)
			(connect_pads
				(clearance 0)
			)
			(min_thickness 0.25)
			(keepout
				(tracks allowed)
				(vias not_allowed)
				(pads allowed)
				(copperpour not_allowed)
				(footprints allowed)
			)
			(placement
				(enabled no)
				(sheetname "")
			)
			(fill
				(thermal_gap 0.5)
				(thermal_bridge_width 0.5)
				(island_removal_mode 0)
			)
			(polygon
				(pts
					(xy 91.8845 -36.1315) (xy 91.8845 -33.2232) (xy 94.9071 -33.2232) (xy 94.9071 -36.1188) (xy 94.9071 -36.449)
					(xy 91.8845 -36.449)
				)
			)
		)
		(zone
			(layer "F.Cu")
			(hatch none 0.5)
			(connect_pads
				(clearance 0)
			)
			(min_thickness 0.25)
			(keepout
				(tracks allowed)
				(vias not_allowed)
				(pads allowed)
				(copperpour not_allowed)
				(footprints allowed)
			)
			(placement
				(enabled no)
				(sheetname "")
			)
			(fill
				(thermal_gap 0.5)
				(thermal_bridge_width 0.5)
				(island_removal_mode 0)
			)
			(polygon
				(pts
					(xy 94.9071 -42.418) (xy 91.8845 -42.418) (xy 91.8845 -39.5224) (xy 91.8845 -39.1922) (xy 94.9071 -39.1922)
					(xy 94.9071 -39.5224)
				)
			)
		)
	)
)
